FILE_TYPE = MACRO_DRAWING;
SET COLOR_WIRE YELLOW;
SET COLOR_PROP MONO;
SET COLOR_DOT WHITE;
SET COLOR_ARC YELLOW;
SET COLOR_BODY GREEN;
SET COLOR_NOTE MONO;
SET PROP_DISPLAY VALUE;
SET PAGE_NUMBER P17;
FORCEADD INTEL_CORP_BPAGE..1
(0 0);
FORCEPROP 1 LAST CDS_CON_LAST_MODIFIED Fri Jun 16 17:48:03 2017
J 0
(-1425 325);
PAINT ORANGE (-1425 325);
DISPLAY INVISIBLE (-1425 325);
FORCEPROP 1 LAST CUSTOM_TXT_CDS <CURRENT_DESIGN_SHEET> OF <TOTAL_DESIGN_SHEETS>
J 0
(-500 25);
PAINT ORANGE (-500 25);
FORCEPROP 1 LAST CUSTOM_TXT_CDS <CON_LAST_MODIFIED>
J 0
(-4000 100);
PAINT ORANGE (-4000 100);
FORCEPROP 2 LAST CUSTOM_TXT_CDS <XR_PAGE_TITLE>
J 0
(-7890 5250);
DISPLAY 0.638298 (-7890 5250);
PAINT PINK (-7890 5250);
DISPLAY INVISIBLE (-7890 5250);
FORCEPROP 1 LAST SCH_TITLE POWER/RESET TIMING G3 > S5 > S0 > S5
J 0
(-7950 50);
DISPLAY 1.212766 (-7950 50);
PAINT ORANGE (-7950 50);
FORCEPROP 2 LAST PAGE_BORDER TRUE
J 0
(-7890 5250);
DISPLAY 0.638298 (-7890 5250);
PAINT PINK (-7890 5250);
DISPLAY INVISIBLE (-7890 5250);
FORCEPROP 2 LAST CDS_LIB mstr_symbols
J 0
(0 0);
PAINT ORANGE (0 0);
DISPLAY INVISIBLE (0 0);
FORCEPROP 1 LAST COMMENT_BODY TRUE
J 0
(12 12);
DISPLAY 0.468085 (12 12);
PAINT GREEN (12 12);
DISPLAY INVISIBLE (12 12);
FORCEPROP 2 LAST CDS_XR_PAGE_TITLE CR-17 : @BASEBOARD_FAB2_LIB.BASEBOARD_FAB2(SCH_1):PAGE17
J 0
(-7890 5250);
DISPLAY 0.638298 (-7890 5250);
PAINT PINK (-7890 5250);
DISPLAY INVISIBLE (-7890 5250);
FORCENOTE
$CDS_IMAGE|POWER SEQUENCE_1210.bmp|7500|3856
(-3975 2825) 0;
DISPLAY LEFT (-3975 2825);
QUIT
